(kicad_pcb
	(version 20260206)
	(generator "pcbnew")
	(generator_version "10.0")
	(general
		(thickness 1.6)
		(legacy_teardrops no)
	)
	(paper "A4")
	(title_block
		(title "panther-plus-userver — 13130-1b_20150205.brd")
		(comment 1 "Honey Badger (Wiwynn) / footprint 624 of 1509 (DIMM4), pads 30-36 of 210")
	)
	(layers
		(0 "F.Cu" signal "TOP")
		(4 "In1.Cu" signal "L2")
		(6 "In2.Cu" signal "L3")
		(8 "In3.Cu" signal "L4")
		(10 "In4.Cu" signal "L5")
		(12 "In5.Cu" signal "L6")
		(14 "In6.Cu" signal "L7")
		(16 "In7.Cu" signal "L8")
		(18 "In8.Cu" signal "L9")
		(20 "In9.Cu" signal "L10")
		(22 "In10.Cu" signal "L11")
		(2 "B.Cu" signal "BOTTOM")
		(9 "F.Adhes" user "F.Adhesive")
		(11 "B.Adhes" user "B.Adhesive")
		(13 "F.Paste" user "Package Geometry/Pastemask Top")
		(15 "B.Paste" user "Package Geometry/Pastemask Bottom")
		(5 "F.SilkS" user "Ref Des/Silkscreen Top")
		(7 "B.SilkS" user "Ref Des/Silkscreen Bottom")
		(1 "F.Mask" user "Board Geometry/Soldermask Top")
		(3 "B.Mask" user "Board Geometry/Soldermask Bottom")
		(17 "Dwgs.User" user "User.Drawings")
		(19 "Cmts.User" user "User.Comments")
		(21 "Eco1.User" user "User.Eco1")
		(23 "Eco2.User" user "User.Eco2")
		(25 "Edge.Cuts" user "Board Geometry/Outline")
		(27 "Margin" user)
		(31 "F.CrtYd" user "Package Geometry/Place Bound Top")
		(29 "B.CrtYd" user "Package Geometry/Place Bound Bottom")
		(35 "F.Fab" user "Ref Des/Assembly Top")
		(33 "B.Fab" user "Ref Des/Assembly Bottom")
	)
	(footprint ""
		(layer "F.Cu")
		(at 159.999934 -5.790692)
		(property "Reference" "DIMM4"
			(at 0 0 0)
			(layer "F.SilkS")
			(hide yes)
			(effects
				(font
					(size 1.27 1.27)
				)
			)
		)
		(property "Value" "DDR3-204P-174-COLAY-1-GP"
			(at -40.682164 -17.468088 0)
			(unlocked yes)
			(layer "F.Fab")
			(hide yes)
			(effects
				(font
					(size 1.016 1.016)
					(thickness 0.1524)
				)
			)
		)
		(property "Device Type" "AS0A626-H8SN-7H-COLAY-1"
			(at -40.682164 -18.992088 0)
			(unlocked yes)
			(layer "F.Fab")
			(hide yes)
			(effects
				(font
					(size 1.016 1.016)
					(thickness 0.1524)
				)
			)
		)
		(duplicate_pad_numbers_are_jumpers no)
		(pad "28" smd custom
			(at -23.550118 -4.106672)
			(size 0.1143 0.1143)
			(layers "F.Cu" "F.Mask" "F.Paste")
			(net "GND")
			(options
				(clearance outline)
				(anchor circle)
			)
			(primitives
				(gr_poly
					(pts
						(xy 0 0.9017) (xy -0.03175 0.89916) (xy -0.0635 0.889) (xy -0.09144 0.87376) (xy -0.11684 0.85344)
						(xy -0.13716 0.82804) (xy -0.1524 0.8001) (xy -0.16256 0.76835) (xy -0.1651 0.7366) (xy -0.1651 0.19685)
						(xy -0.17272 0.18923) (xy -0.17907 0.18034) (xy -0.18669 0.17145) (xy -0.19177 0.16256) (xy -0.19812 0.15367)
						(xy -0.20828 0.13335) (xy -0.21971 0.10287) (xy -0.22225 0.09271) (xy -0.22479 0.08128) (xy -0.22606 0.07112)
						(xy -0.2286 0.05969) (xy -0.2286 0.01651) (xy -0.22606 0.00508) (xy -0.22479 -0.00508) (xy -0.22225 -0.01651)
						(xy -0.21971 -0.02667) (xy -0.20828 -0.05715) (xy -0.19812 -0.07747) (xy -0.19177 -0.08636) (xy -0.18669 -0.09525)
						(xy -0.17907 -0.10414) (xy -0.17272 -0.11303) (xy -0.1651 -0.12065) (xy -0.1651 -0.7366) (xy -0.16256 -0.76835)
						(xy -0.1524 -0.8001) (xy -0.13716 -0.82804) (xy -0.11684 -0.85344) (xy -0.09144 -0.87376) (xy -0.0635 -0.889)
						(xy -0.03175 -0.89916) (xy 0 -0.9017) (xy 0.03175 -0.89916) (xy 0.0635 -0.889) (xy 0.09144 -0.87376)
						(xy 0.11684 -0.85344) (xy 0.13716 -0.82804) (xy 0.1524 -0.8001) (xy 0.16256 -0.76835) (xy 0.1651 -0.7366)
						(xy 0.1651 -0.11938) (xy 0.17272 -0.11176) (xy 0.19812 -0.0762) (xy 0.2032 -0.06604) (xy 0.20701 -0.05715)
						(xy 0.21209 -0.04699) (xy 0.2159 -0.03683) (xy 0.21844 -0.02667) (xy 0.22225 -0.01524) (xy 0.22352 -0.00508)
						(xy 0.22606 0.00508) (xy 0.22733 0.01651) (xy 0.22733 0.02667) (xy 0.2286 0.0381) (xy 0.22733 0.04953)
						(xy 0.22733 0.05969) (xy 0.22606 0.07112) (xy 0.22352 0.08128) (xy 0.22225 0.09144) (xy 0.21844 0.10287)
						(xy 0.2159 0.11303) (xy 0.21209 0.12319) (xy 0.20701 0.13335) (xy 0.2032 0.14224) (xy 0.19812 0.1524)
						(xy 0.17272 0.18796) (xy 0.1651 0.19558) (xy 0.1651 0.7366) (xy 0.16256 0.76835) (xy 0.1524 0.8001)
						(xy 0.13716 0.82804) (xy 0.11684 0.85344) (xy 0.09144 0.87376) (xy 0.0635 0.889) (xy 0.03175 0.89916)
					)
					(width 0)
					(fill yes)
				)
			)
		)
		(pad "29" smd custom
			(at -23.24989 4.106672)
			(size 0.1143 0.1143)
			(layers "F.Cu" "F.Mask" "F.Paste")
			(net "GND")
			(options
				(clearance outline)
				(anchor circle)
			)
			(primitives
				(gr_poly
					(pts
						(xy 0 0.9017) (xy -0.03175 0.89916) (xy -0.0635 0.889) (xy -0.09144 0.87376) (xy -0.11684 0.85344)
						(xy -0.13716 0.82804) (xy -0.1524 0.8001) (xy -0.16256 0.76835) (xy -0.1651 0.7366) (xy -0.1651 -0.13462)
						(xy -0.17272 -0.14224) (xy -0.19812 -0.1778) (xy -0.2032 -0.18796) (xy -0.20701 -0.19685) (xy -0.21209 -0.20701)
						(xy -0.2159 -0.21717) (xy -0.21844 -0.22733) (xy -0.22225 -0.23876) (xy -0.22352 -0.24892) (xy -0.22606 -0.25908)
						(xy -0.22733 -0.27051) (xy -0.22733 -0.28067) (xy -0.2286 -0.2921) (xy -0.22733 -0.30353) (xy -0.22733 -0.31369)
						(xy -0.22606 -0.32512) (xy -0.22352 -0.33528) (xy -0.22225 -0.34544) (xy -0.21844 -0.35687) (xy -0.2159 -0.36703)
						(xy -0.21209 -0.37719) (xy -0.20701 -0.38735) (xy -0.2032 -0.39624) (xy -0.19812 -0.4064) (xy -0.17272 -0.44196)
						(xy -0.1651 -0.44958) (xy -0.1651 -0.7366) (xy -0.16256 -0.76835) (xy -0.1524 -0.8001) (xy -0.13716 -0.82804)
						(xy -0.11684 -0.85344) (xy -0.09144 -0.87376) (xy -0.0635 -0.889) (xy -0.03175 -0.89916) (xy 0 -0.9017)
						(xy 0.03175 -0.89916) (xy 0.0635 -0.889) (xy 0.09144 -0.87376) (xy 0.11684 -0.85344) (xy 0.13716 -0.82804)
						(xy 0.1524 -0.8001) (xy 0.16256 -0.76835) (xy 0.1651 -0.7366) (xy 0.1651 -0.44958) (xy 0.17272 -0.44196)
						(xy 0.19812 -0.4064) (xy 0.2032 -0.39624) (xy 0.20701 -0.38735) (xy 0.21209 -0.37719) (xy 0.2159 -0.36703)
						(xy 0.21844 -0.35687) (xy 0.22225 -0.34544) (xy 0.22352 -0.33528) (xy 0.22606 -0.32512) (xy 0.22733 -0.31369)
						(xy 0.22733 -0.30353) (xy 0.2286 -0.2921) (xy 0.22733 -0.28067) (xy 0.22733 -0.27051) (xy 0.22606 -0.25908)
						(xy 0.22352 -0.24892) (xy 0.22225 -0.23876) (xy 0.21844 -0.22733) (xy 0.2159 -0.21717) (xy 0.21209 -0.20701)
						(xy 0.20701 -0.19685) (xy 0.2032 -0.18796) (xy 0.19812 -0.1778) (xy 0.17272 -0.14224) (xy 0.1651 -0.13462)
						(xy 0.1651 0.7366) (xy 0.16256 0.76835) (xy 0.1524 0.8001) (xy 0.13716 0.82804) (xy 0.11684 0.85344)
						(xy 0.09144 0.87376) (xy 0.0635 0.889) (xy 0.03175 0.89916)
					)
					(width 0)
					(fill yes)
				)
			)
		)
		(pad "30" smd custom
			(at -22.949916 -4.106672)
			(size 0.1143 0.1143)
			(layers "F.Cu" "F.Mask" "F.Paste")
			(net "M_B_RESET#")
			(options
				(clearance outline)
				(anchor circle)
			)
			(primitives
				(gr_poly
					(pts
						(xy 0 0.9017) (xy -0.03175 0.89916) (xy -0.0635 0.889) (xy -0.09144 0.87376) (xy -0.11684 0.85344)
						(xy -0.13716 0.82804) (xy -0.1524 0.8001) (xy -0.16256 0.76835) (xy -0.1651 0.7366) (xy -0.1651 0.44958)
						(xy -0.17272 0.44196) (xy -0.19812 0.4064) (xy -0.2032 0.39624) (xy -0.20701 0.38735) (xy -0.21209 0.37719)
						(xy -0.2159 0.36703) (xy -0.21844 0.35687) (xy -0.22225 0.34544) (xy -0.22352 0.33528) (xy -0.22606 0.32512)
						(xy -0.22733 0.31369) (xy -0.22733 0.30353) (xy -0.2286 0.2921) (xy -0.22733 0.28067) (xy -0.22733 0.27051)
						(xy -0.22606 0.25908) (xy -0.22352 0.24892) (xy -0.22225 0.23876) (xy -0.21844 0.22733) (xy -0.2159 0.21717)
						(xy -0.21209 0.20701) (xy -0.20701 0.19685) (xy -0.2032 0.18796) (xy -0.19812 0.1778) (xy -0.17272 0.14224)
						(xy -0.1651 0.13462) (xy -0.1651 -0.7366) (xy -0.16256 -0.76835) (xy -0.1524 -0.8001) (xy -0.13716 -0.82804)
						(xy -0.11684 -0.85344) (xy -0.09144 -0.87376) (xy -0.0635 -0.889) (xy -0.03175 -0.89916) (xy 0 -0.9017)
						(xy 0.03175 -0.89916) (xy 0.0635 -0.889) (xy 0.09144 -0.87376) (xy 0.11684 -0.85344) (xy 0.13716 -0.82804)
						(xy 0.1524 -0.8001) (xy 0.16256 -0.76835) (xy 0.1651 -0.7366) (xy 0.1651 0.13462) (xy 0.17272 0.14224)
						(xy 0.19812 0.1778) (xy 0.2032 0.18796) (xy 0.20701 0.19685) (xy 0.21209 0.20701) (xy 0.2159 0.21717)
						(xy 0.21844 0.22733) (xy 0.22225 0.23876) (xy 0.22352 0.24892) (xy 0.22606 0.25908) (xy 0.22733 0.27051)
						(xy 0.22733 0.28067) (xy 0.2286 0.2921) (xy 0.22733 0.30353) (xy 0.22733 0.31369) (xy 0.22606 0.32512)
						(xy 0.22352 0.33528) (xy 0.22225 0.34544) (xy 0.21844 0.35687) (xy 0.2159 0.36703) (xy 0.21209 0.37719)
						(xy 0.20701 0.38735) (xy 0.2032 0.39624) (xy 0.19812 0.4064) (xy 0.17272 0.44196) (xy 0.1651 0.44958)
						(xy 0.1651 0.7366) (xy 0.16256 0.76835) (xy 0.1524 0.8001) (xy 0.13716 0.82804) (xy 0.11684 0.85344)
						(xy 0.09144 0.87376) (xy 0.0635 0.889) (xy 0.03175 0.89916)
					)
					(width 0)
					(fill yes)
				)
			)
		)
		(pad "31" smd custom
			(at -22.649942 4.106672)
			(size 0.1143 0.1143)
			(layers "F.Cu" "F.Mask" "F.Paste")
			(net "M_B_DQ14")
			(options
				(clearance outline)
				(anchor circle)
			)
			(primitives
				(gr_poly
					(pts
						(xy 0 0.9017) (xy -0.03175 0.89916) (xy -0.0635 0.889) (xy -0.09144 0.87376) (xy -0.11684 0.85344)
						(xy -0.13716 0.82804) (xy -0.1524 0.8001) (xy -0.16256 0.76835) (xy -0.1651 0.7366) (xy -0.1651 0.11938)
						(xy -0.17272 0.11176) (xy -0.19812 0.0762) (xy -0.2032 0.06604) (xy -0.20701 0.05715) (xy -0.21209 0.04699)
						(xy -0.2159 0.03683) (xy -0.21844 0.02667) (xy -0.22225 0.01524) (xy -0.22352 0.00508) (xy -0.22606 -0.00508)
						(xy -0.22733 -0.01651) (xy -0.22733 -0.02667) (xy -0.2286 -0.0381) (xy -0.22733 -0.04953) (xy -0.22733 -0.05969)
						(xy -0.22606 -0.07112) (xy -0.22352 -0.08128) (xy -0.22225 -0.09144) (xy -0.21844 -0.10287) (xy -0.2159 -0.11303)
						(xy -0.21209 -0.12319) (xy -0.20701 -0.13335) (xy -0.2032 -0.14224) (xy -0.19812 -0.1524) (xy -0.17272 -0.18796)
						(xy -0.1651 -0.19558) (xy -0.1651 -0.7366) (xy -0.16256 -0.76835) (xy -0.1524 -0.8001) (xy -0.13716 -0.82804)
						(xy -0.11684 -0.85344) (xy -0.09144 -0.87376) (xy -0.0635 -0.889) (xy -0.03175 -0.89916) (xy 0 -0.9017)
						(xy 0.03175 -0.89916) (xy 0.0635 -0.889) (xy 0.09144 -0.87376) (xy 0.11684 -0.85344) (xy 0.13716 -0.82804)
						(xy 0.1524 -0.8001) (xy 0.16256 -0.76835) (xy 0.1651 -0.7366) (xy 0.1651 -0.19685) (xy 0.17272 -0.18923)
						(xy 0.17907 -0.18034) (xy 0.18669 -0.17145) (xy 0.19177 -0.16256) (xy 0.19812 -0.15367) (xy 0.20828 -0.13335)
						(xy 0.21971 -0.10287) (xy 0.22225 -0.09271) (xy 0.22479 -0.08128) (xy 0.22606 -0.07112) (xy 0.2286 -0.05969)
						(xy 0.2286 -0.01651) (xy 0.22606 -0.00508) (xy 0.22479 0.00508) (xy 0.22225 0.01651) (xy 0.21971 0.02667)
						(xy 0.20828 0.05715) (xy 0.19812 0.07747) (xy 0.19177 0.08636) (xy 0.18669 0.09525) (xy 0.17907 0.10414)
						(xy 0.17272 0.11303) (xy 0.1651 0.12065) (xy 0.1651 0.7366) (xy 0.16256 0.76835) (xy 0.1524 0.8001)
						(xy 0.13716 0.82804) (xy 0.11684 0.85344) (xy 0.09144 0.87376) (xy 0.0635 0.889) (xy 0.03175 0.89916)
					)
					(width 0)
					(fill yes)
				)
			)
		)
		(pad "32" smd custom
			(at -22.349968 -4.106672)
			(size 0.1143 0.1143)
			(layers "F.Cu" "F.Mask" "F.Paste")
			(net "GND")
			(options
				(clearance outline)
				(anchor circle)
			)
			(primitives
				(gr_poly
					(pts
						(xy 0 0.9017) (xy -0.03175 0.89916) (xy -0.0635 0.889) (xy -0.09144 0.87376) (xy -0.11684 0.85344)
						(xy -0.13716 0.82804) (xy -0.1524 0.8001) (xy -0.16256 0.76835) (xy -0.1651 0.7366) (xy -0.1651 0.19685)
						(xy -0.17272 0.18923) (xy -0.17907 0.18034) (xy -0.18669 0.17145) (xy -0.19177 0.16256) (xy -0.19812 0.15367)
						(xy -0.20828 0.13335) (xy -0.21971 0.10287) (xy -0.22225 0.09271) (xy -0.22479 0.08128) (xy -0.22606 0.07112)
						(xy -0.2286 0.05969) (xy -0.2286 0.01651) (xy -0.22606 0.00508) (xy -0.22479 -0.00508) (xy -0.22225 -0.01651)
						(xy -0.21971 -0.02667) (xy -0.20828 -0.05715) (xy -0.19812 -0.07747) (xy -0.19177 -0.08636) (xy -0.18669 -0.09525)
						(xy -0.17907 -0.10414) (xy -0.17272 -0.11303) (xy -0.1651 -0.12065) (xy -0.1651 -0.7366) (xy -0.16256 -0.76835)
						(xy -0.1524 -0.8001) (xy -0.13716 -0.82804) (xy -0.11684 -0.85344) (xy -0.09144 -0.87376) (xy -0.0635 -0.889)
						(xy -0.03175 -0.89916) (xy 0 -0.9017) (xy 0.03175 -0.89916) (xy 0.0635 -0.889) (xy 0.09144 -0.87376)
						(xy 0.11684 -0.85344) (xy 0.13716 -0.82804) (xy 0.1524 -0.8001) (xy 0.16256 -0.76835) (xy 0.1651 -0.7366)
						(xy 0.1651 -0.11938) (xy 0.17272 -0.11176) (xy 0.19812 -0.0762) (xy 0.2032 -0.06604) (xy 0.20701 -0.05715)
						(xy 0.21209 -0.04699) (xy 0.2159 -0.03683) (xy 0.21844 -0.02667) (xy 0.22225 -0.01524) (xy 0.22352 -0.00508)
						(xy 0.22606 0.00508) (xy 0.22733 0.01651) (xy 0.22733 0.02667) (xy 0.2286 0.0381) (xy 0.22733 0.04953)
						(xy 0.22733 0.05969) (xy 0.22606 0.07112) (xy 0.22352 0.08128) (xy 0.22225 0.09144) (xy 0.21844 0.10287)
						(xy 0.2159 0.11303) (xy 0.21209 0.12319) (xy 0.20701 0.13335) (xy 0.2032 0.14224) (xy 0.19812 0.1524)
						(xy 0.17272 0.18796) (xy 0.1651 0.19558) (xy 0.1651 0.7366) (xy 0.16256 0.76835) (xy 0.1524 0.8001)
						(xy 0.13716 0.82804) (xy 0.11684 0.85344) (xy 0.09144 0.87376) (xy 0.0635 0.889) (xy 0.03175 0.89916)
					)
					(width 0)
					(fill yes)
				)
			)
		)
		(pad "33" smd custom
			(at -22.049994 4.106672)
			(size 0.1143 0.1143)
			(layers "F.Cu" "F.Mask" "F.Paste")
			(net "M_B_DQ15")
			(options
				(clearance outline)
				(anchor circle)
			)
			(primitives
				(gr_poly
					(pts
						(xy 0 0.9017) (xy -0.03175 0.89916) (xy -0.0635 0.889) (xy -0.09144 0.87376) (xy -0.11684 0.85344)
						(xy -0.13716 0.82804) (xy -0.1524 0.8001) (xy -0.16256 0.76835) (xy -0.1651 0.7366) (xy -0.1651 -0.13462)
						(xy -0.17272 -0.14224) (xy -0.19812 -0.1778) (xy -0.2032 -0.18796) (xy -0.20701 -0.19685) (xy -0.21209 -0.20701)
						(xy -0.2159 -0.21717) (xy -0.21844 -0.22733) (xy -0.22225 -0.23876) (xy -0.22352 -0.24892) (xy -0.22606 -0.25908)
						(xy -0.22733 -0.27051) (xy -0.22733 -0.28067) (xy -0.2286 -0.2921) (xy -0.22733 -0.30353) (xy -0.22733 -0.31369)
						(xy -0.22606 -0.32512) (xy -0.22352 -0.33528) (xy -0.22225 -0.34544) (xy -0.21844 -0.35687) (xy -0.2159 -0.36703)
						(xy -0.21209 -0.37719) (xy -0.20701 -0.38735) (xy -0.2032 -0.39624) (xy -0.19812 -0.4064) (xy -0.17272 -0.44196)
						(xy -0.1651 -0.44958) (xy -0.1651 -0.7366) (xy -0.16256 -0.76835) (xy -0.1524 -0.8001) (xy -0.13716 -0.82804)
						(xy -0.11684 -0.85344) (xy -0.09144 -0.87376) (xy -0.0635 -0.889) (xy -0.03175 -0.89916) (xy 0 -0.9017)
						(xy 0.03175 -0.89916) (xy 0.0635 -0.889) (xy 0.09144 -0.87376) (xy 0.11684 -0.85344) (xy 0.13716 -0.82804)
						(xy 0.1524 -0.8001) (xy 0.16256 -0.76835) (xy 0.1651 -0.7366) (xy 0.1651 -0.44958) (xy 0.17272 -0.44196)
						(xy 0.19812 -0.4064) (xy 0.2032 -0.39624) (xy 0.20701 -0.38735) (xy 0.21209 -0.37719) (xy 0.2159 -0.36703)
						(xy 0.21844 -0.35687) (xy 0.22225 -0.34544) (xy 0.22352 -0.33528) (xy 0.22606 -0.32512) (xy 0.22733 -0.31369)
						(xy 0.22733 -0.30353) (xy 0.2286 -0.2921) (xy 0.22733 -0.28067) (xy 0.22733 -0.27051) (xy 0.22606 -0.25908)
						(xy 0.22352 -0.24892) (xy 0.22225 -0.23876) (xy 0.21844 -0.22733) (xy 0.2159 -0.21717) (xy 0.21209 -0.20701)
						(xy 0.20701 -0.19685) (xy 0.2032 -0.18796) (xy 0.19812 -0.1778) (xy 0.17272 -0.14224) (xy 0.1651 -0.13462)
						(xy 0.1651 0.7366) (xy 0.16256 0.76835) (xy 0.1524 0.8001) (xy 0.13716 0.82804) (xy 0.11684 0.85344)
						(xy 0.09144 0.87376) (xy 0.0635 0.889) (xy 0.03175 0.89916)
					)
					(width 0)
					(fill yes)
				)
			)
		)
		(pad "34" smd custom
			(at -21.75002 -4.106672)
			(size 0.1143 0.1143)
			(layers "F.Cu" "F.Mask" "F.Paste")
			(net "M_B_DQ10")
			(options
				(clearance outline)
				(anchor circle)
			)
			(primitives
				(gr_poly
					(pts
						(xy 0 0.9017) (xy -0.03175 0.89916) (xy -0.0635 0.889) (xy -0.09144 0.87376) (xy -0.11684 0.85344)
						(xy -0.13716 0.82804) (xy -0.1524 0.8001) (xy -0.16256 0.76835) (xy -0.1651 0.7366) (xy -0.1651 0.44958)
						(xy -0.17272 0.44196) (xy -0.19812 0.4064) (xy -0.2032 0.39624) (xy -0.20701 0.38735) (xy -0.21209 0.37719)
						(xy -0.2159 0.36703) (xy -0.21844 0.35687) (xy -0.22225 0.34544) (xy -0.22352 0.33528) (xy -0.22606 0.32512)
						(xy -0.22733 0.31369) (xy -0.22733 0.30353) (xy -0.2286 0.2921) (xy -0.22733 0.28067) (xy -0.22733 0.27051)
						(xy -0.22606 0.25908) (xy -0.22352 0.24892) (xy -0.22225 0.23876) (xy -0.21844 0.22733) (xy -0.2159 0.21717)
						(xy -0.21209 0.20701) (xy -0.20701 0.19685) (xy -0.2032 0.18796) (xy -0.19812 0.1778) (xy -0.17272 0.14224)
						(xy -0.1651 0.13462) (xy -0.1651 -0.7366) (xy -0.16256 -0.76835) (xy -0.1524 -0.8001) (xy -0.13716 -0.82804)
						(xy -0.11684 -0.85344) (xy -0.09144 -0.87376) (xy -0.0635 -0.889) (xy -0.03175 -0.89916) (xy 0 -0.9017)
						(xy 0.03175 -0.89916) (xy 0.0635 -0.889) (xy 0.09144 -0.87376) (xy 0.11684 -0.85344) (xy 0.13716 -0.82804)
						(xy 0.1524 -0.8001) (xy 0.16256 -0.76835) (xy 0.1651 -0.7366) (xy 0.1651 0.13462) (xy 0.17272 0.14224)
						(xy 0.19812 0.1778) (xy 0.2032 0.18796) (xy 0.20701 0.19685) (xy 0.21209 0.20701) (xy 0.2159 0.21717)
						(xy 0.21844 0.22733) (xy 0.22225 0.23876) (xy 0.22352 0.24892) (xy 0.22606 0.25908) (xy 0.22733 0.27051)
						(xy 0.22733 0.28067) (xy 0.2286 0.2921) (xy 0.22733 0.30353) (xy 0.22733 0.31369) (xy 0.22606 0.32512)
						(xy 0.22352 0.33528) (xy 0.22225 0.34544) (xy 0.21844 0.35687) (xy 0.2159 0.36703) (xy 0.21209 0.37719)
						(xy 0.20701 0.38735) (xy 0.2032 0.39624) (xy 0.19812 0.4064) (xy 0.17272 0.44196) (xy 0.1651 0.44958)
						(xy 0.1651 0.7366) (xy 0.16256 0.76835) (xy 0.1524 0.8001) (xy 0.13716 0.82804) (xy 0.11684 0.85344)
						(xy 0.09144 0.87376) (xy 0.0635 0.889) (xy 0.03175 0.89916)
					)
					(width 0)
					(fill yes)
				)
			)
		)
	)
)
